FILE_TYPE=LIBRARY_PARTS;
primitive 'ADM809';
  pin
    'VCC':
      PIN_NUMBER='(3)';
      PIN_TYPE='POWER';
      NO_LOAD_CHECK='Both';
      NO_IO_CHECK='Both';
      ALLOW_CONNECT='TRUE';
    'RESET_N':
      PIN_NUMBER='(2)';
      OUTPUT_LOAD='(10.0,-10.0)';
  end_pin;
  body
    PART_NAME='ADM809';
    POWER_PINS='(GND:1)';
    PHYS_DES_PREFIX='U';
    CLASS='IC';
  end_body;
end_primitive;

END.
